# T6G (Grand Teton) — schematic netlist excerpt (pin names and nets, part order shuffled) for the footprints in the layout excerpt that follows; sources: Cadence DE-HDL packaged netlist, KiCad conversion of 04192023_DAF0TMB3IC0_F0TG_MB_C_brd_V02_OCP.brd

PR519  Q_RES  1.5 1% EMPTY  pkg 0402LF  page 225 : A = SW_PVDD11_S3_P1_SW2_RC ; B = GND
R3205  Q_RES  0 5% CHIP  pkg 0402LF  page 138 : A = FB_BMC_ISOLATE_R2 ; B = FB_BMC_ISOLATE1

(kicad_pcb
	(version 20260206)
	(generator "pcbnew")
	(generator_version "10.0")
	(general
		(thickness 1.6)
		(legacy_teardrops no)
	)
	(paper "A4")
	(title_block
		(title "04192023_DAF0TMB3IC0_F0TG_MB_C_brd_V02_OCP.brd")
		(comment 1 "Grand Teton / footprints 2208-2209 of 8354")
	)
	(layers
		(0 "F.Cu" signal "TOP")
		(4 "In1.Cu" signal "GND")
		(6 "In2.Cu" signal "IN1")
		(8 "In3.Cu" signal "GND1")
		(10 "In4.Cu" signal "IN2")
		(12 "In5.Cu" signal "GND2")
		(14 "In6.Cu" signal "IN3")
		(16 "In7.Cu" signal "GND3")
		(18 "In8.Cu" signal "VCC")
		(20 "In9.Cu" signal "VCC1")
		(22 "In10.Cu" signal "GND4")
		(24 "In11.Cu" signal "IN4")
		(26 "In12.Cu" signal "GND5")
		(28 "In13.Cu" signal "IN5")
		(30 "In14.Cu" signal "GND6")
		(32 "In15.Cu" signal "IN6")
		(34 "In16.Cu" signal "GND7")
		(2 "B.Cu" signal "BOTTOM")
		(9 "F.Adhes" user "F.Adhesive")
		(11 "B.Adhes" user "B.Adhesive")
		(13 "F.Paste" user "Package Geometry/Pastemask Top")
		(15 "B.Paste" user "Package Geometry/Pastemask Bottom")
		(5 "F.SilkS" user "Ref Des/Silkscreen Top")
		(7 "B.SilkS" user "Ref Des/Silkscreen Bottom")
		(1 "F.Mask" user "Board Geometry/Soldermask Top")
		(3 "B.Mask" user "Board Geometry/Soldermask Bottom")
		(17 "Dwgs.User" user "User.Drawings")
		(19 "Cmts.User" user "User.Comments")
		(21 "Eco1.User" user "User.Eco1")
		(23 "Eco2.User" user "User.Eco2")
		(25 "Edge.Cuts" user "Board Geometry/Outline")
		(27 "Margin" user)
		(31 "F.CrtYd" user "Package Geometry/Place Bound Top")
		(29 "B.CrtYd" user "Package Geometry/Place Bound Bottom")
		(35 "F.Fab" user "Ref Des/Assembly Top")
		(33 "B.Fab" user "Ref Des/Assembly Bottom")
	)
	(footprint ""
		(layer "F.Cu")
		(at 50.20183 -33.575498 90)
		(property "Reference" "R3205"
			(at 0 0 90)
			(layer "F.SilkS")
			(hide yes)
			(effects
				(font
					(size 1.27 1.27)
				)
			)
		)
		(property "Value" ""
			(at 0 0 90)
			(layer "F.Fab")
			(effects
				(font
					(size 1.27 1.27)
				)
			)
		)
		(duplicate_pad_numbers_are_jumpers no)
		(fp_line
			(start 0.7874 -0.4064)
			(end 0.7874 0.4064)
			(stroke
				(width 0.1524)
				(type default)
			)
			(layer "F.SilkS")
		)
		(fp_line
			(start -0.7874 -0.4064)
			(end 0.7874 -0.4064)
			(stroke
				(width 0.1524)
				(type default)
			)
			(layer "F.SilkS")
		)
		(fp_line
			(start 0.7874 0.4064)
			(end -0.7874 0.4064)
			(stroke
				(width 0.1524)
				(type default)
			)
			(layer "F.SilkS")
		)
		(fp_line
			(start -0.7874 0.4064)
			(end -0.7874 -0.4064)
			(stroke
				(width 0.1524)
				(type default)
			)
			(layer "F.SilkS")
		)
		(fp_line
			(start -0.12065 -0.305054)
			(end -0.12065 -0.2794)
			(stroke
				(width 0.1)
				(type default)
			)
			(layer "F.Fab")
		)
		(fp_line
			(start -0.67945 -0.305054)
			(end -0.12065 -0.305054)
			(stroke
				(width 0.1)
				(type default)
			)
			(layer "F.Fab")
		)
		(fp_line
			(start 0.67945 -0.3048)
			(end 0.67945 0.3048)
			(stroke
				(width 0.1)
				(type default)
			)
			(layer "F.Fab")
		)
		(fp_line
			(start 0.12065 -0.3048)
			(end 0.67945 -0.3048)
			(stroke
				(width 0.1)
				(type default)
			)
			(layer "F.Fab")
		)
		(fp_line
			(start 0.12065 -0.2794)
			(end 0.12065 -0.3048)
			(stroke
				(width 0.1)
				(type default)
			)
			(layer "F.Fab")
		)
		(fp_line
			(start -0.12065 -0.2794)
			(end 0.12065 -0.2794)
			(stroke
				(width 0.1)
				(type default)
			)
			(layer "F.Fab")
		)
		(fp_line
			(start 0.120396 0.2794)
			(end -0.12065 0.2794)
			(stroke
				(width 0.1)
				(type default)
			)
			(layer "F.Fab")
		)
		(fp_line
			(start -0.12065 0.2794)
			(end -0.12065 0.3048)
			(stroke
				(width 0.1)
				(type default)
			)
			(layer "F.Fab")
		)
		(fp_line
			(start 0.67945 0.3048)
			(end 0.120396 0.3048)
			(stroke
				(width 0.1)
				(type default)
			)
			(layer "F.Fab")
		)
		(fp_line
			(start 0.120396 0.3048)
			(end 0.120396 0.2794)
			(stroke
				(width 0.1)
				(type default)
			)
			(layer "F.Fab")
		)
		(fp_line
			(start -0.12065 0.3048)
			(end -0.67945 0.3048)
			(stroke
				(width 0.1)
				(type default)
			)
			(layer "F.Fab")
		)
		(fp_line
			(start -0.67945 0.3048)
			(end -0.67945 -0.305054)
			(stroke
				(width 0.1)
				(type default)
			)
			(layer "F.Fab")
		)
		(pad "1" smd circle
			(at -0.40005 0 90)
			(size 0 0)
			(layers "F.Cu" "F.Mask" "F.Paste")
			(net "FB_BMC_ISOLATE_R2")
		)
		(pad "2" smd circle
			(at 0.40005 0 90)
			(size 0 0)
			(layers "F.Cu" "F.Mask" "F.Paste")
			(net "FB_BMC_ISOLATE1")
		)
	)
	(footprint ""
		(layer "F.Cu")
		(at 187.569348 -349.58655 90)
		(property "Reference" "PR519"
			(at 0 0 90)
			(layer "F.SilkS")
			(hide yes)
			(effects
				(font
					(size 1.27 1.27)
				)
			)
		)
		(property "Value" ""
			(at 0 0 90)
			(layer "F.Fab")
			(effects
				(font
					(size 1.27 1.27)
				)
			)
		)
		(duplicate_pad_numbers_are_jumpers no)
		(fp_line
			(start 0.7874 -0.4064)
			(end 0.7874 0.4064)
			(stroke
				(width 0.1524)
				(type default)
			)
			(layer "F.SilkS")
		)
		(fp_line
			(start -0.7874 -0.4064)
			(end 0.7874 -0.4064)
			(stroke
				(width 0.1524)
				(type default)
			)
			(layer "F.SilkS")
		)
		(fp_line
			(start 0.7874 0.4064)
			(end -0.7874 0.4064)
			(stroke
				(width 0.1524)
				(type default)
			)
			(layer "F.SilkS")
		)
		(fp_line
			(start -0.7874 0.4064)
			(end -0.7874 -0.4064)
			(stroke
				(width 0.1524)
				(type default)
			)
			(layer "F.SilkS")
		)
		(fp_line
			(start -0.12065 -0.305054)
			(end -0.12065 -0.2794)
			(stroke
				(width 0.1)
				(type default)
			)
			(layer "F.Fab")
		)
		(fp_line
			(start -0.67945 -0.305054)
			(end -0.12065 -0.305054)
			(stroke
				(width 0.1)
				(type default)
			)
			(layer "F.Fab")
		)
		(fp_line
			(start 0.67945 -0.3048)
			(end 0.67945 0.3048)
			(stroke
				(width 0.1)
				(type default)
			)
			(layer "F.Fab")
		)
		(fp_line
			(start 0.12065 -0.3048)
			(end 0.67945 -0.3048)
			(stroke
				(width 0.1)
				(type default)
			)
			(layer "F.Fab")
		)
		(fp_line
			(start 0.12065 -0.2794)
			(end 0.12065 -0.3048)
			(stroke
				(width 0.1)
				(type default)
			)
			(layer "F.Fab")
		)
		(fp_line
			(start -0.12065 -0.2794)
			(end 0.12065 -0.2794)
			(stroke
				(width 0.1)
				(type default)
			)
			(layer "F.Fab")
		)
		(fp_line
			(start 0.120396 0.2794)
			(end -0.12065 0.2794)
			(stroke
				(width 0.1)
				(type default)
			)
			(layer "F.Fab")
		)
		(fp_line
			(start -0.12065 0.2794)
			(end -0.12065 0.3048)
			(stroke
				(width 0.1)
				(type default)
			)
			(layer "F.Fab")
		)
		(fp_line
			(start 0.67945 0.3048)
			(end 0.120396 0.3048)
			(stroke
				(width 0.1)
				(type default)
			)
			(layer "F.Fab")
		)
		(fp_line
			(start 0.120396 0.3048)
			(end 0.120396 0.2794)
			(stroke
				(width 0.1)
				(type default)
			)
			(layer "F.Fab")
		)
		(fp_line
			(start -0.12065 0.3048)
			(end -0.67945 0.3048)
			(stroke
				(width 0.1)
				(type default)
			)
			(layer "F.Fab")
		)
		(fp_line
			(start -0.67945 0.3048)
			(end -0.67945 -0.305054)
			(stroke
				(width 0.1)
				(type default)
			)
			(layer "F.Fab")
		)
		(pad "1" smd circle
			(at -0.40005 0 90)
			(size 0 0)
			(layers "F.Cu" "F.Mask" "F.Paste")
			(net "SW_PVDD11_S3_P1_SW2_RC")
		)
		(pad "2" smd circle
			(at 0.40005 0 90)
			(size 0 0)
			(layers "F.Cu" "F.Mask" "F.Paste")
			(net "GND")
		)
	)
)
